# BASEBOARD_FAB2 (Tioga Pass) — schematic netlist excerpt (pin names and nets, part order shuffled) for the footprints in the layout excerpt that follows; sources: Cadence DE-HDL packaged netlist, KiCad conversion of Wiwynn_Tioga_Pass_MB.brd

J4B1  SCONN288_H44441004  SCONN  pkg PIP  page 49
  \12v\(1)  = P12V_NVDIMM_DEF
  VSS(93)  = GND
  DQ(4)  = M_D_DQ<5>
  VSS(92)  = GND
  DQ(0)  = M_D_DQ<1>
  VSS(91)  = GND
  DQS9P  = M_D_DQS_DP<9>
  DQS9N  = M_D_DQS_DN<9>
  VSS(90)  = GND
  DQ(6)  = M_D_DQ<7>
  VSS(89)  = GND
  DQ(2)  = M_D_DQ<3>
  VSS(88)  = GND
  DQ(12)  = M_D_DQ<13>
  VSS(87)  = GND
  DQ(8)  = M_D_DQ<9>
  VSS(86)  = GND
  DQS10P  = M_D_DQS_DP<10>
  DQS10N  = M_D_DQS_DN<10>
  VSS(85)  = GND
  DQ(14)  = M_D_DQ<15>
  VSS(84)  = GND
  DQ(10)  = M_D_DQ<11>
  VSS(83)  = GND
  DQ(20)  = M_D_DQ<21>
  VSS(82)  = GND
  DQ(16)  = M_D_DQ<17>
  VSS(81)  = GND
  DQS11P  = M_D_DQS_DP<11>
  DQS11N  = M_D_DQS_DN<11>
  VSS(80)  = GND
  DQ(22)  = M_D_DQ<23>
  VSS(79)  = GND
  DQ(18)  = M_D_DQ<19>
  VSS(78)  = GND
  DQ(28)  = M_D_DQ<29>
  VSS(77)  = GND
  DQ(24)  = M_D_DQ<25>
  VSS(76)  = GND
  DQS12P  = M_D_DQS_DP<12>
  DQS12N  = M_D_DQS_DN<12>
  VSS(75)  = GND
  DQ(30)  = M_D_DQ<31>
  VSS(74)  = GND
  DQ(26)  = M_D_DQ<27>
  VSS(73)  = GND
  CB(4)  = M_D_ECC<5>
  VSS(72)  = GND
  CB(0)  = M_D_ECC<1>
  VSS(71)  = GND
  DQS17P  = M_D_DQS_DP<17>
  DQS17N  = M_D_DQS_DN<17>
  VSS(70)  = GND
  CB(6)  = M_D_ECC<7>
  VSS(69)  = GND
  CB(2)  = M_D_ECC<3>
  VSS(68)  = GND
  RESET_N  = M_DEF_RST_N
  VDD(25)  = PVDDQ_DEF
  CKE(0)  = M_D_CKE<0>
  VDD(24)  = PVDDQ_DEF
  ACT_N  = M_D_ACT_N
  BG(0)  = M_D_BG<0>
  VDD(23)  = PVDDQ_DEF
  A12  = M_D_MA<12>
  A9  = M_D_MA<9>
  VDD(22)  = PVDDQ_DEF
  A8  = M_D_MA<8>
  A6  = M_D_MA<6>
  VDD(21)  = PVDDQ_DEF
  A3  = M_D_MA<3>
  A1  = M_D_MA<1>
  VDD(20)  = PVDDQ_DEF
  CK0P  = M_D_CLK_DP<0>
  CK0N  = M_D_CLK_DN<0>
  VDD(19)  = PVDDQ_DEF
  VTT(1)  = PVTT_DEF
  EVENT_N  = FM_DIMM_EVENT_COD_N
  A0  = M_D_MA<0>
  VDD(18)  = PVDDQ_DEF
  BA(0)  = M_D_BA<0>
  A16_RAS_N  = M_D_MA<16>
  VDD(17)  = PVDDQ_DEF
  S0_N  = M_D_CS_N<0>
  VDD(16)  = PVDDQ_DEF
  A15_CAS_N  = M_D_MA<15>
  ODT(0)  = M_D_ODT<0>
  VDD(15)  = PVDDQ_DEF
  S1_N  = M_D_CS_N<1>
  VDD(14)  = PVDDQ_DEF
  ODT(1)  = M_D_ODT<1>
  VDD(13)  = PVDDQ_DEF
  S2_N_C(0)  = M_D_CS_N<2>
  VSS(67)  = GND
  DQ(36)  = M_D_DQ<37>
  VSS(66)  = GND
  DQ(32)  = M_D_DQ<33>
  VSS(65)  = GND
  DQS13P  = M_D_DQS_DP<13>
  DQS13N  = M_D_DQS_DN<13>
  VSS(64)  = GND
  DQ(38)  = M_D_DQ<39>
  VSS(63)  = GND
  DQ(34)  = M_D_DQ<35>
  VSS(62)  = GND
  DQ(44)  = M_D_DQ<45>
  VSS(61)  = GND
  DQ(40)  = M_D_DQ<41>
  VSS(60)  = GND
  DQS14P  = M_D_DQS_DP<14>
  DQS14N  = M_D_DQS_DN<14>
  VSS(59)  = GND
  DQ(46)  = M_D_DQ<47>
  VSS(58)  = GND
  DQ(42)  = M_D_DQ<43>
  VSS(57)  = GND
  DQ(52)  = M_D_DQ<53>
  VSS(56)  = GND
  DQ(48)  = M_D_DQ<49>
  VSS(55)  = GND
  DQS15P  = M_D_DQS_DP<15>
  DQS15N  = M_D_DQS_DN<15>
  VSS(54)  = GND
  DQ(54)  = M_D_DQ<55>
  VSS(53)  = GND
  DQ(50)  = M_D_DQ<51>
  VSS(52)  = GND
  DQ(60)  = M_D_DQ<61>
  VSS(51)  = GND
  DQ(56)  = M_D_DQ<57>
  VSS(50)  = GND
  DQS16P  = M_D_DQS_DP<16>
  DQS16N  = M_D_DQS_DN<16>
  VSS(49)  = GND
  DQ(62)  = M_D_DQ<63>
  VSS(48)  = GND
  DQ(58)  = M_D_DQ<59>
  VSS(47)  = GND
  SA(0)  = GND
  SA(1)  = GND
  SCL  = SMB_DDR_DEF_VPP_SCL
  VPP(4)  = PVPP_DEF
  VPP(3)  = PVPP_DEF
  RFU(2)  = TP_CH_D_DIMM_D0_RFU_2
  \12v\(0)  = P12V_NVDIMM_DEF
  VREFCA  = M_D_VREF
  VSS(46)  = GND
  DQ(5)  = M_D_DQ<4>
  VSS(45)  = GND
  DQ(1)  = M_D_DQ<0>
  VSS(44)  = GND
  DQS0N  = M_D_DQS_DN<0>
  DQS0P  = M_D_DQS_DP<0>
  VSS(43)  = GND
  DQ(7)  = M_D_DQ<6>
  VSS(42)  = GND
  DQ(3)  = M_D_DQ<2>
  VSS(41)  = GND
  DQ(13)  = M_D_DQ<12>
  VSS(40)  = GND
  DQ(9)  = M_D_DQ<8>
  VSS(39)  = GND
  DQS1N  = M_D_DQS_DN<1>
  DQS1P  = M_D_DQS_DP<1>
  VSS(38)  = GND
  DQ(15)  = M_D_DQ<14>
  VSS(37)  = GND
  DQ(11)  = M_D_DQ<10>
  VSS(36)  = GND
  DQ(21)  = M_D_DQ<20>
  VSS(35)  = GND
  DQ(17)  = M_D_DQ<16>
  VSS(34)  = GND
  DQS2N  = M_D_DQS_DN<2>
  DQS2P  = M_D_DQS_DP<2>
  VSS(33)  = GND
  DQ(23)  = M_D_DQ<22>
  VSS(32)  = GND
  DQ(19)  = M_D_DQ<18>
  VSS(31)  = GND
  DQ(29)  = M_D_DQ<28>
  VSS(30)  = GND
  DQ(25)  = M_D_DQ<24>
  VSS(29)  = GND
  DQS3N  = M_D_DQS_DN<3>
  DQS3P  = M_D_DQS_DP<3>
  VSS(28)  = GND
  DQ(31)  = M_D_DQ<30>
  VSS(27)  = GND
  DQ(27)  = M_D_DQ<26>
  VSS(26)  = GND
  CB(5)  = M_D_ECC<4>
  VSS(25)  = GND
  CB(1)  = M_D_ECC<0>
  VSS(24)  = GND
  DQS8N  = M_D_DQS_DN<8>
  DQS8P  = M_D_DQS_DP<8>
  VSS(23)  = GND
  CB(7)  = M_D_ECC<6>
  VSS(22)  = GND
  CB(3)  = M_D_ECC<2>
  VSS(21)  = GND
  CKE(1)  = M_D_CKE<1>
  VDD(12)  = PVDDQ_DEF
  RFU(0)  = TP_CH_D_DIMM_D0_RFU_0
  VDD(11)  = PVDDQ_DEF
  BG(1)  = M_D_BG<1>
  ALERT_N  = M_D_ALERT_N
  VDD(10)  = PVDDQ_DEF
  A11  = M_D_MA<11>
  A7  = M_D_MA<7>
  VDD(9)  = PVDDQ_DEF
  A5  = M_D_MA<5>
  A4  = M_D_MA<4>
  VDD(8)  = PVDDQ_DEF
  A2  = M_D_MA<2>
  VDD(7)  = PVDDQ_DEF
  CK1P  = M_D_CLK_DP<1>
  CK1N  = M_D_CLK_DN<1>
  VDD(6)  = PVDDQ_DEF
  VTT(0)  = PVTT_DEF
  PAR  = M_D_PAR
  VDD(5)  = PVDDQ_DEF
  BA(1)  = M_D_BA<1>
  A10  = M_D_MA<10>
  VDD(4)  = PVDDQ_DEF
  RFU(1)  = TP_CH_D_DIMM_D0_RFU_1
  A14_WE_N  = M_D_MA<14>
  VDD(3)  = PVDDQ_DEF
  SAVE_N_NC  = FM_ADR_COMPLETE_DEF_N
  VDD(2)  = PVDDQ_DEF
  A13  = M_D_MA<13>
  VDD(1)  = PVDDQ_DEF
  A17  = M_D_MA<17>
  C(2)  = M_D_C<2>
  VDD(0)  = PVDDQ_DEF
  S3_N_C(1)  = M_D_CS_N<3>
  SA(2)  = GND
  VSS(20)  = GND
  DQ(37)  = M_D_DQ<36>
  VSS(19)  = GND
  DQ(33)  = M_D_DQ<32>
  VSS(18)  = GND
  DQS4N  = M_D_DQS_DN<4>
  DQS4P  = M_D_DQS_DP<4>
  VSS(17)  = GND
  DQ(39)  = M_D_DQ<38>
  VSS(16)  = GND
  DQ(35)  = M_D_DQ<34>
  VSS(15)  = GND
  DQ(45)  = M_D_DQ<44>
  VSS(14)  = GND
  DQ(41)  = M_D_DQ<40>
  VSS(13)  = GND
  DQS5N  = M_D_DQS_DN<5>
  DQS5P  = M_D_DQS_DP<5>
  VSS(12)  = GND
  DQ(47)  = M_D_DQ<46>
  VSS(11)  = GND
  DQ(43)  = M_D_DQ<42>
  VSS(10)  = GND
  DQ(53)  = M_D_DQ<52>
  VSS(9)  = GND
  DQ(49)  = M_D_DQ<48>
  VSS(8)  = GND
  DQS6N  = M_D_DQS_DN<6>
  DQS6P  = M_D_DQS_DP<6>
  VSS(7)  = GND
  DQ(55)  = M_D_DQ<54>
  VSS(6)  = GND
  DQ(51)  = M_D_DQ<50>
  VSS(5)  = GND
  DQ(61)  = M_D_DQ<60>
  VSS(4)  = GND
  DQ(57)  = M_D_DQ<56>
  VSS(3)  = GND
  DQS7N  = M_D_DQS_DN<7>
  DQS7P  = M_D_DQS_DP<7>
  VSS(2)  = GND
  DQ(63)  = M_D_DQ<62>
  VSS(1)  = GND
  DQ(59)  = M_D_DQ<58>
  VSS(0)  = GND
  VDDSPD  = PVPP_DEF
  SDA  = SMB_DDR_DEF_VPP_SDA
  VPP(1)  = PVPP_DEF
  VPP(0)  = PVPP_DEF
  VPP(2)  = PVPP_DEF

(kicad_pcb
	(version 20260206)
	(generator "pcbnew")
	(generator_version "10.0")
	(general
		(thickness 1.6)
		(legacy_teardrops no)
	)
	(paper "A4")
	(title_block
		(title "Wiwynn_Tioga_Pass_MB.brd")
		(comment 1 "Tioga Pass / footprint 990 of 4770 (J4B1), pads 203-251 of 291")
	)
	(layers
		(0 "F.Cu" signal "TOP")
		(4 "In1.Cu" signal "L2GND")
		(6 "In2.Cu" signal "L3")
		(8 "In3.Cu" signal "L4GND")
		(10 "In4.Cu" signal "L5")
		(12 "In5.Cu" signal "L6GND")
		(14 "In6.Cu" signal "L7VCC")
		(16 "In7.Cu" signal "L8VCC")
		(18 "In8.Cu" signal "L9GND")
		(20 "In9.Cu" signal "L10")
		(22 "In10.Cu" signal "L11GND")
		(24 "In11.Cu" signal "L12")
		(26 "In12.Cu" signal "L13GND")
		(2 "B.Cu" signal "BOTTOM")
		(9 "F.Adhes" user "F.Adhesive")
		(11 "B.Adhes" user "B.Adhesive")
		(13 "F.Paste" user "Package Geometry/Pastemask Top")
		(15 "B.Paste" user "Package Geometry/Pastemask Bottom")
		(5 "F.SilkS" user "Ref Des/Silkscreen Top")
		(7 "B.SilkS" user "Ref Des/Silkscreen Bottom")
		(1 "F.Mask" user "Board Geometry/Soldermask Top")
		(3 "B.Mask" user "Board Geometry/Soldermask Bottom")
		(17 "Dwgs.User" user "User.Drawings")
		(19 "Cmts.User" user "User.Comments")
		(21 "Eco1.User" user "User.Eco1")
		(23 "Eco2.User" user "User.Eco2")
		(25 "Edge.Cuts" user "Board Geometry/Outline")
		(27 "Margin" user)
		(31 "F.CrtYd" user "Package Geometry/Place Bound Top")
		(29 "B.CrtYd" user "Package Geometry/Place Bound Bottom")
		(35 "F.Fab" user "Ref Des/Assembly Top")
		(33 "B.Fab" user "Ref Des/Assembly Bottom")
	)
	(footprint ""
		(layer "F.Cu")
		(at 194.700398 -133.0706 90)
		(property "Reference" "J4B1"
			(at -5.087112 42.28211 0)
			(unlocked yes)
			(layer "F.SilkS")
			(effects
				(font
					(size 0.7874 0.5842)
					(thickness 0.1524)
				)
				(justify left)
			)
		)
		(property "Value" ""
			(at 0 0 90)
			(layer "F.Fab")
			(effects
				(font
					(size 1.27 1.27)
				)
			)
		)
		(duplicate_pad_numbers_are_jumpers no)
		(pad "200" smd rect
			(at 4.59994 46.74997 90)
			(size 1.8034 0.508)
			(layers "F.Cu" "F.Mask" "F.Paste")
			(net "GND")
		)
		(pad "201" smd rect
			(at 4.59994 47.600108 90)
			(size 1.8034 0.508)
			(layers "F.Cu" "F.Mask" "F.Paste")
			(net "M_D_ECC<2>")
		)
		(pad "202" smd rect
			(at 4.59994 48.449992 90)
			(size 1.8034 0.508)
			(layers "F.Cu" "F.Mask" "F.Paste")
			(net "GND")
		)
		(pad "203" smd rect
			(at 4.59994 49.299876 90)
			(size 1.8034 0.508)
			(layers "F.Cu" "F.Mask" "F.Paste")
			(net "M_D_CKE<1>")
		)
		(pad "204" smd rect
			(at 4.59994 50.150014 90)
			(size 1.8034 0.508)
			(layers "F.Cu" "F.Mask" "F.Paste")
			(net "PVDDQ_DEF")
		)
		(pad "205" smd rect
			(at 4.59994 50.999898 90)
			(size 1.8034 0.508)
			(layers "F.Cu" "F.Mask" "F.Paste")
			(net "TP_CH_D_DIMM_D0_RFU_0")
		)
		(pad "206" smd rect
			(at 4.59994 51.850036 90)
			(size 1.8034 0.508)
			(layers "F.Cu" "F.Mask" "F.Paste")
			(net "PVDDQ_DEF")
		)
		(pad "207" smd rect
			(at 4.59994 52.69992 90)
			(size 1.8034 0.508)
			(layers "F.Cu" "F.Mask" "F.Paste")
			(net "M_D_BG<1>")
		)
		(pad "208" smd rect
			(at 4.59994 53.550058 90)
			(size 1.8034 0.508)
			(layers "F.Cu" "F.Mask" "F.Paste")
			(net "M_D_ALERT_N")
		)
		(pad "209" smd rect
			(at 4.59994 54.399942 90)
			(size 1.8034 0.508)
			(layers "F.Cu" "F.Mask" "F.Paste")
			(net "PVDDQ_DEF")
		)
		(pad "210" smd rect
			(at 4.59994 55.25008 90)
			(size 1.8034 0.508)
			(layers "F.Cu" "F.Mask" "F.Paste")
			(net "M_D_MA<11>")
		)
		(pad "211" smd rect
			(at 4.59994 56.099964 90)
			(size 1.8034 0.508)
			(layers "F.Cu" "F.Mask" "F.Paste")
			(net "M_D_MA<7>")
		)
		(pad "212" smd rect
			(at 4.59994 56.950102 90)
			(size 1.8034 0.508)
			(layers "F.Cu" "F.Mask" "F.Paste")
			(net "PVDDQ_DEF")
		)
		(pad "213" smd rect
			(at 4.59994 57.799986 90)
			(size 1.8034 0.508)
			(layers "F.Cu" "F.Mask" "F.Paste")
			(net "M_D_MA<5>")
		)
		(pad "214" smd rect
			(at 4.59994 58.650124 90)
			(size 1.8034 0.508)
			(layers "F.Cu" "F.Mask" "F.Paste")
			(net "M_D_MA<4>")
		)
		(pad "215" smd rect
			(at 4.59994 59.500008 90)
			(size 1.8034 0.508)
			(layers "F.Cu" "F.Mask" "F.Paste")
			(net "PVDDQ_DEF")
		)
		(pad "216" smd rect
			(at 4.59994 60.349892 90)
			(size 1.8034 0.508)
			(layers "F.Cu" "F.Mask" "F.Paste")
			(net "M_D_MA<2>")
		)
		(pad "217" smd rect
			(at 4.59994 61.20003 90)
			(size 1.8034 0.508)
			(layers "F.Cu" "F.Mask" "F.Paste")
			(net "PVDDQ_DEF")
		)
		(pad "218" smd rect
			(at 4.59994 62.049914 90)
			(size 1.8034 0.508)
			(layers "F.Cu" "F.Mask" "F.Paste")
			(net "M_D_CLK_DP<1>")
		)
		(pad "219" smd rect
			(at 4.59994 62.900052 90)
			(size 1.8034 0.508)
			(layers "F.Cu" "F.Mask" "F.Paste")
			(net "M_D_CLK_DN<1>")
		)
		(pad "220" smd rect
			(at 4.59994 63.749936 90)
			(size 1.8034 0.508)
			(layers "F.Cu" "F.Mask" "F.Paste")
			(net "PVDDQ_DEF")
		)
		(pad "221" smd rect
			(at 4.59994 64.600074 90)
			(size 1.8034 0.508)
			(layers "F.Cu" "F.Mask" "F.Paste")
			(net "PVTT_DEF")
		)
		(pad "222" smd rect
			(at 4.59994 70.550024 90)
			(size 1.8034 0.508)
			(layers "F.Cu" "F.Mask" "F.Paste")
			(net "M_D_PAR")
		)
		(pad "223" smd rect
			(at 4.59994 71.399908 90)
			(size 1.8034 0.508)
			(layers "F.Cu" "F.Mask" "F.Paste")
			(net "PVDDQ_DEF")
		)
		(pad "224" smd rect
			(at 4.59994 72.250046 90)
			(size 1.8034 0.508)
			(layers "F.Cu" "F.Mask" "F.Paste")
			(net "M_D_BA<1>")
		)
		(pad "225" smd rect
			(at 4.59994 73.09993 90)
			(size 1.8034 0.508)
			(layers "F.Cu" "F.Mask" "F.Paste")
			(net "M_D_MA<10>")
		)
		(pad "226" smd rect
			(at 4.59994 73.950068 90)
			(size 1.8034 0.508)
			(layers "F.Cu" "F.Mask" "F.Paste")
			(net "PVDDQ_DEF")
		)
		(pad "227" smd rect
			(at 4.59994 74.799952 90)
			(size 1.8034 0.508)
			(layers "F.Cu" "F.Mask" "F.Paste")
			(net "TP_CH_D_DIMM_D0_RFU_1")
		)
		(pad "228" smd rect
			(at 4.59994 75.65009 90)
			(size 1.8034 0.508)
			(layers "F.Cu" "F.Mask" "F.Paste")
			(net "M_D_MA<14>")
		)
		(pad "229" smd rect
			(at 4.59994 76.499974 90)
			(size 1.8034 0.508)
			(layers "F.Cu" "F.Mask" "F.Paste")
			(net "PVDDQ_DEF")
		)
		(pad "230" smd rect
			(at 4.59994 77.350112 90)
			(size 1.8034 0.508)
			(layers "F.Cu" "F.Mask" "F.Paste")
			(net "FM_ADR_COMPLETE_DEF_N")
		)
		(pad "231" smd rect
			(at 4.59994 78.199996 90)
			(size 1.8034 0.508)
			(layers "F.Cu" "F.Mask" "F.Paste")
			(net "PVDDQ_DEF")
		)
		(pad "232" smd rect
			(at 4.59994 79.04988 90)
			(size 1.8034 0.508)
			(layers "F.Cu" "F.Mask" "F.Paste")
			(net "M_D_MA<13>")
		)
		(pad "233" smd rect
			(at 4.59994 79.900018 90)
			(size 1.8034 0.508)
			(layers "F.Cu" "F.Mask" "F.Paste")
			(net "PVDDQ_DEF")
		)
		(pad "234" smd rect
			(at 4.59994 80.749902 90)
			(size 1.8034 0.508)
			(layers "F.Cu" "F.Mask" "F.Paste")
			(net "M_D_MA<17>")
		)
		(pad "235" smd rect
			(at 4.59994 81.60004 90)
			(size 1.8034 0.508)
			(layers "F.Cu" "F.Mask" "F.Paste")
			(net "M_D_C<2>")
		)
		(pad "236" smd rect
			(at 4.59994 82.449924 90)
			(size 1.8034 0.508)
			(layers "F.Cu" "F.Mask" "F.Paste")
			(net "PVDDQ_DEF")
		)
		(pad "237" smd rect
			(at 4.59994 83.300062 90)
			(size 1.8034 0.508)
			(layers "F.Cu" "F.Mask" "F.Paste")
			(net "M_D_CS_N<3>")
		)
		(pad "238" smd rect
			(at 4.59994 84.149946 90)
			(size 1.8034 0.508)
			(layers "F.Cu" "F.Mask" "F.Paste")
			(net "GND")
		)
		(pad "239" smd rect
			(at 4.59994 85.000084 90)
			(size 1.8034 0.508)
			(layers "F.Cu" "F.Mask" "F.Paste")
			(net "GND")
		)
		(pad "240" smd rect
			(at 4.59994 85.849968 90)
			(size 1.8034 0.508)
			(layers "F.Cu" "F.Mask" "F.Paste")
			(net "M_D_DQ<36>")
		)
		(pad "241" smd rect
			(at 4.59994 86.700106 90)
			(size 1.8034 0.508)
			(layers "F.Cu" "F.Mask" "F.Paste")
			(net "GND")
		)
		(pad "242" smd rect
			(at 4.59994 87.54999 90)
			(size 1.8034 0.508)
			(layers "F.Cu" "F.Mask" "F.Paste")
			(net "M_D_DQ<32>")
		)
		(pad "243" smd rect
			(at 4.59994 88.399874 90)
			(size 1.8034 0.508)
			(layers "F.Cu" "F.Mask" "F.Paste")
			(net "GND")
		)
		(pad "244" smd rect
			(at 4.59994 89.250012 90)
			(size 1.8034 0.508)
			(layers "F.Cu" "F.Mask" "F.Paste")
			(net "M_D_DQS_DN<4>")
		)
		(pad "245" smd rect
			(at 4.59994 90.099896 90)
			(size 1.8034 0.508)
			(layers "F.Cu" "F.Mask" "F.Paste")
			(net "M_D_DQS_DP<4>")
		)
		(pad "246" smd rect
			(at 4.59994 90.950034 90)
			(size 1.8034 0.508)
			(layers "F.Cu" "F.Mask" "F.Paste")
			(net "GND")
		)
		(pad "247" smd rect
			(at 4.59994 91.799918 90)
			(size 1.8034 0.508)
			(layers "F.Cu" "F.Mask" "F.Paste")
			(net "M_D_DQ<38>")
		)
		(pad "248" smd rect
			(at 4.59994 92.650056 90)
			(size 1.8034 0.508)
			(layers "F.Cu" "F.Mask" "F.Paste")
			(net "GND")
		)
	)
)
